(kicad_pcb
	(version 20260206)
	(generator "pcbnew")
	(generator_version "10.0")
	(general
		(thickness 1.6)
		(legacy_teardrops no)
	)
	(paper "A4")
	(title_block
		(title "12092022_DA0F0TFB6D0_F0T_FAN_BOARD_MP5048_D_brd_v02_OCP.brd")
		(comment 1 "Grand Teton / footprints 161-167 of 924")
	)
	(layers
		(0 "F.Cu" signal "TOP")
		(4 "In1.Cu" signal "GND")
		(6 "In2.Cu" signal "IN1")
		(8 "In3.Cu" signal "IN2")
		(10 "In4.Cu" signal "GND1")
		(2 "B.Cu" signal "BOTTOM")
		(9 "F.Adhes" user "F.Adhesive")
		(11 "B.Adhes" user "B.Adhesive")
		(13 "F.Paste" user "Package Geometry/Pastemask Top")
		(15 "B.Paste" user "Package Geometry/Pastemask Bottom")
		(5 "F.SilkS" user "Ref Des/Silkscreen Top")
		(7 "B.SilkS" user "Ref Des/Silkscreen Bottom")
		(1 "F.Mask" user "Board Geometry/Soldermask Top")
		(3 "B.Mask" user "Board Geometry/Soldermask Bottom")
		(17 "Dwgs.User" user "User.Drawings")
		(19 "Cmts.User" user "User.Comments")
		(21 "Eco1.User" user "User.Eco1")
		(23 "Eco2.User" user "User.Eco2")
		(25 "Edge.Cuts" user "Board Geometry/Outline")
		(27 "Margin" user)
		(31 "F.CrtYd" user "Package Geometry/Place Bound Top")
		(29 "B.CrtYd" user "Package Geometry/Place Bound Bottom")
		(35 "F.Fab" user "Ref Des/Assembly Top")
		(33 "B.Fab" user "Ref Des/Assembly Bottom")
	)
	(footprint ""
		(layer "F.Cu")
		(at 42.291 -259.461)
		(property "Reference" "PR5"
			(at 0 0 0)
			(layer "F.SilkS")
			(hide yes)
			(effects
				(font
					(size 1.27 1.27)
				)
			)
		)
		(property "Value" ""
			(at 0 0 0)
			(layer "F.Fab")
			(effects
				(font
					(size 1.27 1.27)
				)
			)
		)
		(duplicate_pad_numbers_are_jumpers no)
		(fp_line
			(start -0.7874 -0.4064)
			(end 0.7874 -0.4064)
			(stroke
				(width 0.1524)
				(type default)
			)
			(layer "F.SilkS")
		)
		(fp_line
			(start -0.7874 0.4064)
			(end -0.7874 -0.4064)
			(stroke
				(width 0.1524)
				(type default)
			)
			(layer "F.SilkS")
		)
		(fp_line
			(start 0.7874 -0.4064)
			(end 0.7874 0.4064)
			(stroke
				(width 0.1524)
				(type default)
			)
			(layer "F.SilkS")
		)
		(fp_line
			(start 0.7874 0.4064)
			(end -0.7874 0.4064)
			(stroke
				(width 0.1524)
				(type default)
			)
			(layer "F.SilkS")
		)
		(fp_line
			(start -0.67945 -0.305054)
			(end -0.12065 -0.305054)
			(stroke
				(width 0.1)
				(type default)
			)
			(layer "F.Fab")
		)
		(fp_line
			(start -0.67945 0.3048)
			(end -0.67945 -0.305054)
			(stroke
				(width 0.1)
				(type default)
			)
			(layer "F.Fab")
		)
		(fp_line
			(start -0.12065 -0.305054)
			(end -0.12065 -0.2794)
			(stroke
				(width 0.1)
				(type default)
			)
			(layer "F.Fab")
		)
		(fp_line
			(start -0.12065 -0.2794)
			(end 0.12065 -0.2794)
			(stroke
				(width 0.1)
				(type default)
			)
			(layer "F.Fab")
		)
		(fp_line
			(start -0.12065 0.2794)
			(end -0.12065 0.3048)
			(stroke
				(width 0.1)
				(type default)
			)
			(layer "F.Fab")
		)
		(fp_line
			(start -0.12065 0.3048)
			(end -0.67945 0.3048)
			(stroke
				(width 0.1)
				(type default)
			)
			(layer "F.Fab")
		)
		(fp_line
			(start 0.120396 0.2794)
			(end -0.12065 0.2794)
			(stroke
				(width 0.1)
				(type default)
			)
			(layer "F.Fab")
		)
		(fp_line
			(start 0.120396 0.3048)
			(end 0.120396 0.2794)
			(stroke
				(width 0.1)
				(type default)
			)
			(layer "F.Fab")
		)
		(fp_line
			(start 0.12065 -0.3048)
			(end 0.67945 -0.3048)
			(stroke
				(width 0.1)
				(type default)
			)
			(layer "F.Fab")
		)
		(fp_line
			(start 0.12065 -0.2794)
			(end 0.12065 -0.3048)
			(stroke
				(width 0.1)
				(type default)
			)
			(layer "F.Fab")
		)
		(fp_line
			(start 0.67945 -0.3048)
			(end 0.67945 0.3048)
			(stroke
				(width 0.1)
				(type default)
			)
			(layer "F.Fab")
		)
		(fp_line
			(start 0.67945 0.3048)
			(end 0.120396 0.3048)
			(stroke
				(width 0.1)
				(type default)
			)
			(layer "F.Fab")
		)
		(pad "1" smd circle
			(at -0.40005 0)
			(size 0 0)
			(layers "F.Cu" "F.Mask" "F.Paste")
			(net "FAN_0_P3V_R")
		)
		(pad "2" smd circle
			(at 0.40005 0)
			(size 0 0)
			(layers "F.Cu" "F.Mask" "F.Paste")
			(net "FAN_0_MODE")
		)
	)
	(footprint ""
		(layer "F.Cu")
		(at 43.561 -173.863)
		(property "Reference" "R5098"
			(at 0 0 0)
			(layer "F.SilkS")
			(hide yes)
			(effects
				(font
					(size 1.27 1.27)
				)
			)
		)
		(property "Value" ""
			(at 0 0 0)
			(layer "F.Fab")
			(effects
				(font
					(size 1.27 1.27)
				)
			)
		)
		(duplicate_pad_numbers_are_jumpers no)
		(fp_line
			(start -0.7874 -0.4064)
			(end 0.7874 -0.4064)
			(stroke
				(width 0.1524)
				(type default)
			)
			(layer "F.SilkS")
		)
		(fp_line
			(start -0.7874 0.4064)
			(end -0.7874 -0.4064)
			(stroke
				(width 0.1524)
				(type default)
			)
			(layer "F.SilkS")
		)
		(fp_line
			(start 0.7874 -0.4064)
			(end 0.7874 0.4064)
			(stroke
				(width 0.1524)
				(type default)
			)
			(layer "F.SilkS")
		)
		(fp_line
			(start 0.7874 0.4064)
			(end -0.7874 0.4064)
			(stroke
				(width 0.1524)
				(type default)
			)
			(layer "F.SilkS")
		)
		(fp_line
			(start -0.67945 -0.305054)
			(end -0.12065 -0.305054)
			(stroke
				(width 0.1)
				(type default)
			)
			(layer "F.Fab")
		)
		(fp_line
			(start -0.67945 0.3048)
			(end -0.67945 -0.305054)
			(stroke
				(width 0.1)
				(type default)
			)
			(layer "F.Fab")
		)
		(fp_line
			(start -0.12065 -0.305054)
			(end -0.12065 -0.2794)
			(stroke
				(width 0.1)
				(type default)
			)
			(layer "F.Fab")
		)
		(fp_line
			(start -0.12065 -0.2794)
			(end 0.12065 -0.2794)
			(stroke
				(width 0.1)
				(type default)
			)
			(layer "F.Fab")
		)
		(fp_line
			(start -0.12065 0.2794)
			(end -0.12065 0.3048)
			(stroke
				(width 0.1)
				(type default)
			)
			(layer "F.Fab")
		)
		(fp_line
			(start -0.12065 0.3048)
			(end -0.67945 0.3048)
			(stroke
				(width 0.1)
				(type default)
			)
			(layer "F.Fab")
		)
		(fp_line
			(start 0.120396 0.2794)
			(end -0.12065 0.2794)
			(stroke
				(width 0.1)
				(type default)
			)
			(layer "F.Fab")
		)
		(fp_line
			(start 0.120396 0.3048)
			(end 0.120396 0.2794)
			(stroke
				(width 0.1)
				(type default)
			)
			(layer "F.Fab")
		)
		(fp_line
			(start 0.12065 -0.3048)
			(end 0.67945 -0.3048)
			(stroke
				(width 0.1)
				(type default)
			)
			(layer "F.Fab")
		)
		(fp_line
			(start 0.12065 -0.2794)
			(end 0.12065 -0.3048)
			(stroke
				(width 0.1)
				(type default)
			)
			(layer "F.Fab")
		)
		(fp_line
			(start 0.67945 -0.3048)
			(end 0.67945 0.3048)
			(stroke
				(width 0.1)
				(type default)
			)
			(layer "F.Fab")
		)
		(fp_line
			(start 0.67945 0.3048)
			(end 0.120396 0.3048)
			(stroke
				(width 0.1)
				(type default)
			)
			(layer "F.Fab")
		)
		(pad "1" smd circle
			(at -0.40005 0)
			(size 0 0)
			(layers "F.Cu" "F.Mask" "F.Paste")
			(net "FAN_2_OK_LED")
		)
		(pad "2" smd circle
			(at 0.40005 0)
			(size 0 0)
			(layers "F.Cu" "F.Mask" "F.Paste")
			(net "FAN_2_OK_R_LED")
		)
	)
	(footprint ""
		(layer "F.Cu")
		(at 32.893 -114.709956)
		(property "Reference" "D280"
			(at 0.254 1.452626 0)
			(unlocked yes)
			(layer "F.SilkS")
			(effects
				(font
					(size 0.7874 0.5842)
					(thickness 0.1524)
				)
				(justify left)
			)
		)
		(property "Value" ""
			(at 0 0 0)
			(layer "F.Fab")
			(effects
				(font
					(size 1.27 1.27)
				)
			)
		)
		(duplicate_pad_numbers_are_jumpers no)
		(fp_line
			(start -0.854964 -0.450088)
			(end -0.854964 0.450088)
			(stroke
				(width 0.1524)
				(type default)
			)
			(layer "F.SilkS")
		)
		(fp_line
			(start -0.854964 0.450088)
			(end 0.925068 0.450088)
			(stroke
				(width 0.1524)
				(type default)
			)
			(layer "F.SilkS")
		)
		(fp_line
			(start 0.845058 0.4064)
			(end 0.845058 -0.381)
			(stroke
				(width 0.1524)
				(type default)
			)
			(layer "F.SilkS")
		)
		(fp_line
			(start 0.870458 -0.2794)
			(end 0.845058 0.4064)
			(stroke
				(width 0.1524)
				(type default)
			)
			(layer "F.SilkS")
		)
		(fp_line
			(start 0.94488 -0.450088)
			(end -0.854964 -0.450088)
			(stroke
				(width 0.1524)
				(type default)
			)
			(layer "F.SilkS")
		)
		(fp_line
			(start 0.94488 0.450088)
			(end 0.94488 -0.450088)
			(stroke
				(width 0.1524)
				(type default)
			)
			(layer "F.SilkS")
		)
		(fp_line
			(start -0.54991 -0.350012)
			(end -0.54991 0.350012)
			(stroke
				(width 0.1)
				(type default)
			)
			(layer "F.Fab")
		)
		(fp_line
			(start -0.54991 0.350012)
			(end 0.54991 0.350012)
			(stroke
				(width 0.1)
				(type default)
			)
			(layer "F.Fab")
		)
		(fp_line
			(start 0.54991 -0.350012)
			(end -0.54991 -0.350012)
			(stroke
				(width 0.1)
				(type default)
			)
			(layer "F.Fab")
		)
		(fp_line
			(start 0.54991 0.350012)
			(end 0.54991 -0.350012)
			(stroke
				(width 0.1)
				(type default)
			)
			(layer "F.Fab")
		)
		(fp_text user "+"
			(at -0.635 0.251206 180)
			(unlocked yes)
			(layer "F.SilkS")
			(effects
				(font
					(size 1.905 1.4224)
					(thickness 0.1524)
				)
				(justify left)
			)
		)
		(fp_text user "-"
			(at 1.27 1.013206 180)
			(unlocked yes)
			(layer "F.SilkS")
			(effects
				(font
					(size 1.905 1.4224)
					(thickness 0.1524)
				)
				(justify left)
			)
		)
		(fp_text user "+"
			(at -0.808228 0.239014 180)
			(unlocked yes)
			(layer "F.Fab")
			(effects
				(font
					(size 1.905 1.4224)
					(thickness 0.1524)
				)
				(justify left)
			)
		)
		(fp_text user "-"
			(at 2.48539 0.239014 180)
			(unlocked yes)
			(layer "F.Fab")
			(effects
				(font
					(size 1.905 1.4224)
					(thickness 0.1524)
				)
				(justify left)
			)
		)
		(pad "A" smd rect
			(at -0.424942 0)
			(size 0.5588 0.6096)
			(layers "F.Cu" "F.Mask" "F.Paste")
			(net "GND")
		)
		(pad "C" smd rect
			(at 0.424942 0 180)
			(size 0.5588 0.6096)
			(layers "F.Cu" "F.Mask" "F.Paste")
			(net "FAN_2_PWM_IL_R")
		)
	)
	(footprint ""
		(layer "F.Cu")
		(at 30.353 -189.23)
		(property "Reference" "R4955"
			(at 0 0 0)
			(layer "F.SilkS")
			(hide yes)
			(effects
				(font
					(size 1.27 1.27)
				)
			)
		)
		(property "Value" ""
			(at 0 0 0)
			(layer "F.Fab")
			(effects
				(font
					(size 1.27 1.27)
				)
			)
		)
		(duplicate_pad_numbers_are_jumpers no)
		(fp_line
			(start -0.7874 -0.4064)
			(end 0.7874 -0.4064)
			(stroke
				(width 0.1524)
				(type default)
			)
			(layer "F.SilkS")
		)
		(fp_line
			(start -0.7874 0.4064)
			(end -0.7874 -0.4064)
			(stroke
				(width 0.1524)
				(type default)
			)
			(layer "F.SilkS")
		)
		(fp_line
			(start 0.7874 -0.4064)
			(end 0.7874 0.4064)
			(stroke
				(width 0.1524)
				(type default)
			)
			(layer "F.SilkS")
		)
		(fp_line
			(start 0.7874 0.4064)
			(end -0.7874 0.4064)
			(stroke
				(width 0.1524)
				(type default)
			)
			(layer "F.SilkS")
		)
		(fp_line
			(start -0.67945 -0.305054)
			(end -0.12065 -0.305054)
			(stroke
				(width 0.1)
				(type default)
			)
			(layer "F.Fab")
		)
		(fp_line
			(start -0.67945 0.3048)
			(end -0.67945 -0.305054)
			(stroke
				(width 0.1)
				(type default)
			)
			(layer "F.Fab")
		)
		(fp_line
			(start -0.12065 -0.305054)
			(end -0.12065 -0.2794)
			(stroke
				(width 0.1)
				(type default)
			)
			(layer "F.Fab")
		)
		(fp_line
			(start -0.12065 -0.2794)
			(end 0.12065 -0.2794)
			(stroke
				(width 0.1)
				(type default)
			)
			(layer "F.Fab")
		)
		(fp_line
			(start -0.12065 0.2794)
			(end -0.12065 0.3048)
			(stroke
				(width 0.1)
				(type default)
			)
			(layer "F.Fab")
		)
		(fp_line
			(start -0.12065 0.3048)
			(end -0.67945 0.3048)
			(stroke
				(width 0.1)
				(type default)
			)
			(layer "F.Fab")
		)
		(fp_line
			(start 0.120396 0.2794)
			(end -0.12065 0.2794)
			(stroke
				(width 0.1)
				(type default)
			)
			(layer "F.Fab")
		)
		(fp_line
			(start 0.120396 0.3048)
			(end 0.120396 0.2794)
			(stroke
				(width 0.1)
				(type default)
			)
			(layer "F.Fab")
		)
		(fp_line
			(start 0.12065 -0.3048)
			(end 0.67945 -0.3048)
			(stroke
				(width 0.1)
				(type default)
			)
			(layer "F.Fab")
		)
		(fp_line
			(start 0.12065 -0.2794)
			(end 0.12065 -0.3048)
			(stroke
				(width 0.1)
				(type default)
			)
			(layer "F.Fab")
		)
		(fp_line
			(start 0.67945 -0.3048)
			(end 0.67945 0.3048)
			(stroke
				(width 0.1)
				(type default)
			)
			(layer "F.Fab")
		)
		(fp_line
			(start 0.67945 0.3048)
			(end 0.120396 0.3048)
			(stroke
				(width 0.1)
				(type default)
			)
			(layer "F.Fab")
		)
		(pad "1" smd circle
			(at -0.40005 0)
			(size 0 0)
			(layers "F.Cu" "F.Mask" "F.Paste")
			(net "P3V3_AUX")
		)
		(pad "2" smd circle
			(at 0.40005 0)
			(size 0 0)
			(layers "F.Cu" "F.Mask" "F.Paste")
			(net "P52V_FAN_4_BUFF_EN")
		)
	)
	(footprint ""
		(layer "F.Cu")
		(at 36.83 -198.374 90)
		(property "Reference" "R5691"
			(at 0 0 90)
			(layer "F.SilkS")
			(hide yes)
			(effects
				(font
					(size 1.27 1.27)
				)
			)
		)
		(property "Value" ""
			(at 0 0 90)
			(layer "F.Fab")
			(effects
				(font
					(size 1.27 1.27)
				)
			)
		)
		(duplicate_pad_numbers_are_jumpers no)
		(fp_line
			(start 0.7874 -0.4064)
			(end 0.7874 0.4064)
			(stroke
				(width 0.1524)
				(type default)
			)
			(layer "F.SilkS")
		)
		(fp_line
			(start -0.7874 -0.4064)
			(end 0.7874 -0.4064)
			(stroke
				(width 0.1524)
				(type default)
			)
			(layer "F.SilkS")
		)
		(fp_line
			(start 0.7874 0.4064)
			(end -0.7874 0.4064)
			(stroke
				(width 0.1524)
				(type default)
			)
			(layer "F.SilkS")
		)
		(fp_line
			(start -0.7874 0.4064)
			(end -0.7874 -0.4064)
			(stroke
				(width 0.1524)
				(type default)
			)
			(layer "F.SilkS")
		)
		(fp_line
			(start -0.12065 -0.305054)
			(end -0.12065 -0.2794)
			(stroke
				(width 0.1)
				(type default)
			)
			(layer "F.Fab")
		)
		(fp_line
			(start -0.67945 -0.305054)
			(end -0.12065 -0.305054)
			(stroke
				(width 0.1)
				(type default)
			)
			(layer "F.Fab")
		)
		(fp_line
			(start 0.67945 -0.3048)
			(end 0.67945 0.3048)
			(stroke
				(width 0.1)
				(type default)
			)
			(layer "F.Fab")
		)
		(fp_line
			(start 0.12065 -0.3048)
			(end 0.67945 -0.3048)
			(stroke
				(width 0.1)
				(type default)
			)
			(layer "F.Fab")
		)
		(fp_line
			(start 0.12065 -0.2794)
			(end 0.12065 -0.3048)
			(stroke
				(width 0.1)
				(type default)
			)
			(layer "F.Fab")
		)
		(fp_line
			(start -0.12065 -0.2794)
			(end 0.12065 -0.2794)
			(stroke
				(width 0.1)
				(type default)
			)
			(layer "F.Fab")
		)
		(fp_line
			(start 0.120396 0.2794)
			(end -0.12065 0.2794)
			(stroke
				(width 0.1)
				(type default)
			)
			(layer "F.Fab")
		)
		(fp_line
			(start -0.12065 0.2794)
			(end -0.12065 0.3048)
			(stroke
				(width 0.1)
				(type default)
			)
			(layer "F.Fab")
		)
		(fp_line
			(start 0.67945 0.3048)
			(end 0.120396 0.3048)
			(stroke
				(width 0.1)
				(type default)
			)
			(layer "F.Fab")
		)
		(fp_line
			(start 0.120396 0.3048)
			(end 0.120396 0.2794)
			(stroke
				(width 0.1)
				(type default)
			)
			(layer "F.Fab")
		)
		(fp_line
			(start -0.12065 0.3048)
			(end -0.67945 0.3048)
			(stroke
				(width 0.1)
				(type default)
			)
			(layer "F.Fab")
		)
		(fp_line
			(start -0.67945 0.3048)
			(end -0.67945 -0.305054)
			(stroke
				(width 0.1)
				(type default)
			)
			(layer "F.Fab")
		)
		(pad "1" smd rect
			(at -0.40005 0 270)
			(size 0.4572 0.508)
			(layers "F.Cu" "F.Mask" "F.Paste")
			(net "P12V_LED_FAN1")
		)
		(pad "2" smd rect
			(at 0.40005 0 270)
			(size 0.4572 0.508)
			(layers "F.Cu" "F.Mask" "F.Paste")
			(net "P12V_LED_R_FAN1")
		)
	)
	(footprint ""
		(layer "F.Cu")
		(at 17.399 -110.49 180)
		(property "Reference" "U363"
			(at -1.651 1.37033 0)
			(unlocked yes)
			(layer "F.SilkS")
			(effects
				(font
					(size 0.7874 0.5842)
					(thickness 0.1524)
				)
				(justify left)
			)
		)
		(property "Value" ""
			(at 0 0 180)
			(layer "F.Fab")
			(effects
				(font
					(size 1.27 1.27)
				)
			)
		)
		(duplicate_pad_numbers_are_jumpers no)
		(fp_line
			(start 1.335278 1.100074)
			(end 1.335278 -1.100074)
			(stroke
				(width 0.1524)
				(type default)
			)
			(layer "F.SilkS")
		)
		(fp_line
			(start 1.335278 -1.100074)
			(end -1.335278 -1.100074)
			(stroke
				(width 0.1524)
				(type default)
			)
			(layer "F.SilkS")
		)
		(fp_line
			(start -1.335278 1.100074)
			(end 1.335278 1.100074)
			(stroke
				(width 0.1524)
				(type default)
			)
			(layer "F.SilkS")
		)
		(fp_line
			(start -1.335278 -1.100074)
			(end -1.335278 1.100074)
			(stroke
				(width 0.1524)
				(type default)
			)
			(layer "F.SilkS")
		)
		(fp_line
			(start 0.674878 1.100074)
			(end 0.674878 -1.100074)
			(stroke
				(width 0.1)
				(type default)
			)
			(layer "F.Fab")
		)
		(fp_line
			(start 0.674878 -1.100074)
			(end -0.674878 -1.100074)
			(stroke
				(width 0.1)
				(type default)
			)
			(layer "F.Fab")
		)
		(fp_line
			(start -0.674878 1.100074)
			(end 0.674878 1.100074)
			(stroke
				(width 0.1)
				(type default)
			)
			(layer "F.Fab")
		)
		(fp_line
			(start -0.674878 -1.100074)
			(end -0.674878 1.100074)
			(stroke
				(width 0.1)
				(type default)
			)
			(layer "F.Fab")
		)
		(pad "D" smd rect
			(at 0.8001 0 90)
			(size 0.6096 0.8128)
			(layers "F.Cu" "F.Mask" "F.Paste")
			(net "FAN_5_FAIL_LED_R_N")
		)
		(pad "G" smd rect
			(at -0.8001 -0.649986 90)
			(size 0.6096 0.8128)
			(layers "F.Cu" "F.Mask" "F.Paste")
			(net "FAN_5_FAIL_R_LED")
		)
		(pad "S" smd rect
			(at -0.8001 0.649986 90)
			(size 0.6096 0.8128)
			(layers "F.Cu" "F.Mask" "F.Paste")
			(net "GND")
		)
	)
	(footprint ""
		(layer "F.Cu")
		(at 14.224 -304.546 -90)
		(property "Reference" "D259"
			(at 1.02616 1.22555 90)
			(unlocked yes)
			(layer "F.SilkS")
			(effects
				(font
					(size 0.7874 0.5842)
					(thickness 0.1524)
				)
				(justify left)
			)
		)
		(property "Value" ""
			(at 0 0 270)
			(layer "F.Fab")
			(effects
				(font
					(size 1.27 1.27)
				)
			)
		)
		(duplicate_pad_numbers_are_jumpers no)
		(fp_line
			(start -0.854964 0.450088)
			(end 0.925068 0.450088)
			(stroke
				(width 0.1524)
				(type default)
			)
			(layer "F.SilkS")
		)
		(fp_line
			(start 0.94488 0.450088)
			(end 0.94488 -0.450088)
			(stroke
				(width 0.1524)
				(type default)
			)
			(layer "F.SilkS")
		)
		(fp_line
			(start 0.845058 0.4064)
			(end 0.845058 -0.381)
			(stroke
				(width 0.1524)
				(type default)
			)
			(layer "F.SilkS")
		)
		(fp_line
			(start 0.870458 -0.2794)
			(end 0.845058 0.4064)
			(stroke
				(width 0.1524)
				(type default)
			)
			(layer "F.SilkS")
		)
		(fp_line
			(start -0.854964 -0.450088)
			(end -0.854964 0.450088)
			(stroke
				(width 0.1524)
				(type default)
			)
			(layer "F.SilkS")
		)
		(fp_line
			(start 0.94488 -0.450088)
			(end -0.854964 -0.450088)
			(stroke
				(width 0.1524)
				(type default)
			)
			(layer "F.SilkS")
		)
		(fp_line
			(start -0.54991 0.350012)
			(end 0.54991 0.350012)
			(stroke
				(width 0.1)
				(type default)
			)
			(layer "F.Fab")
		)
		(fp_line
			(start 0.54991 0.350012)
			(end 0.54991 -0.350012)
			(stroke
				(width 0.1)
				(type default)
			)
			(layer "F.Fab")
		)
		(fp_line
			(start -0.54991 -0.350012)
			(end -0.54991 0.350012)
			(stroke
				(width 0.1)
				(type default)
			)
			(layer "F.Fab")
		)
		(fp_line
			(start 0.54991 -0.350012)
			(end -0.54991 -0.350012)
			(stroke
				(width 0.1)
				(type default)
			)
			(layer "F.Fab")
		)
		(fp_text user "+"
			(at -1.143 0.22225 90)
			(unlocked yes)
			(layer "F.SilkS")
			(effects
				(font
					(size 1.905 1.4224)
					(thickness 0.1524)
				)
				(justify left)
			)
		)
		(fp_text user "-"
			(at 1.5113 -0.62103 90)
			(unlocked yes)
			(layer "F.SilkS")
			(effects
				(font
					(size 1.905 1.4224)
					(thickness 0.1524)
				)
				(justify left)
			)
		)
		(fp_text user "+"
			(at -0.808228 0.239014 90)
			(unlocked yes)
			(layer "F.Fab")
			(effects
				(font
					(size 1.905 1.4224)
					(thickness 0.1524)
				)
				(justify left)
			)
		)
		(fp_text user "-"
			(at 2.48539 0.239014 90)
			(unlocked yes)
			(layer "F.Fab")
			(effects
				(font
					(size 1.905 1.4224)
					(thickness 0.1524)
				)
				(justify left)
			)
		)
		(pad "A" smd rect
			(at -0.424942 0 270)
			(size 0.5588 0.6096)
			(layers "F.Cu" "F.Mask" "F.Paste")
			(net "GND")
		)
		(pad "C" smd rect
			(at 0.424942 0 90)
			(size 0.5588 0.6096)
			(layers "F.Cu" "F.Mask" "F.Paste")
			(net "FAN_7_TACH_OL_D")
		)
	)
)
